# BASEBOARD_FAB2 (Tioga Pass) — schematic netlist excerpt (pin names and nets, part order shuffled) for the footprints in the layout excerpt that follows; sources: Cadence DE-HDL packaged netlist, KiCad conversion of Wiwynn_Tioga_Pass_MB.brd

C7G40  CAP  1.0UF 16V 10% X6S  pkg 0402  page 216 : A = VR_PVDDQ_ABC_PH2_VCIN ; B = GND
C1A13  CAP  0.22UF 16V 10% X7R  pkg 0402  page 227 : A = P5V_STBY ; B = GND
CT36  CAP_A  0.1UF 16V 10% X7R  pkg 0402V  page 204 : A = VR_PVCCIN_CPU0_AIREF5 ; B = GND

(kicad_pcb
	(version 20260206)
	(generator "pcbnew")
	(generator_version "10.0")
	(general
		(thickness 1.6)
		(legacy_teardrops no)
	)
	(paper "A4")
	(title_block
		(title "Wiwynn_Tioga_Pass_MB.brd")
		(comment 1 "Tioga Pass / footprints 1187-1189 of 4770")
	)
	(layers
		(0 "F.Cu" signal "TOP")
		(4 "In1.Cu" signal "L2GND")
		(6 "In2.Cu" signal "L3")
		(8 "In3.Cu" signal "L4GND")
		(10 "In4.Cu" signal "L5")
		(12 "In5.Cu" signal "L6GND")
		(14 "In6.Cu" signal "L7VCC")
		(16 "In7.Cu" signal "L8VCC")
		(18 "In8.Cu" signal "L9GND")
		(20 "In9.Cu" signal "L10")
		(22 "In10.Cu" signal "L11GND")
		(24 "In11.Cu" signal "L12")
		(26 "In12.Cu" signal "L13GND")
		(2 "B.Cu" signal "BOTTOM")
		(9 "F.Adhes" user "F.Adhesive")
		(11 "B.Adhes" user "B.Adhesive")
		(13 "F.Paste" user "Package Geometry/Pastemask Top")
		(15 "B.Paste" user "Package Geometry/Pastemask Bottom")
		(5 "F.SilkS" user "Ref Des/Silkscreen Top")
		(7 "B.SilkS" user "Ref Des/Silkscreen Bottom")
		(1 "F.Mask" user "Board Geometry/Soldermask Top")
		(3 "B.Mask" user "Board Geometry/Soldermask Bottom")
		(17 "Dwgs.User" user "User.Drawings")
		(19 "Cmts.User" user "User.Comments")
		(21 "Eco1.User" user "User.Eco1")
		(23 "Eco2.User" user "User.Eco2")
		(25 "Edge.Cuts" user "Board Geometry/Outline")
		(27 "Margin" user)
		(31 "F.CrtYd" user "Package Geometry/Place Bound Top")
		(29 "B.CrtYd" user "Package Geometry/Place Bound Bottom")
		(35 "F.Fab" user "Ref Des/Assembly Top")
		(33 "B.Fab" user "Ref Des/Assembly Bottom")
	)
	(footprint ""
		(layer "F.Cu")
		(at 1.651 -143.256 90)
		(property "Reference" "C1A13"
			(at 0 0 90)
			(layer "F.SilkS")
			(hide yes)
			(effects
				(font
					(size 1.27 1.27)
				)
			)
		)
		(property "Value" ""
			(at 0 0 90)
			(layer "F.Fab")
			(effects
				(font
					(size 1.27 1.27)
				)
			)
		)
		(duplicate_pad_numbers_are_jumpers no)
		(fp_rect
			(start 0.3048 0.9906)
			(end -0.3048 -0.1016)
			(stroke
				(width 0)
				(type default)
			)
			(fill no)
			(layer "F.CrtYd")
		)
		(fp_line
			(start 0.3048 -0.1016)
			(end -0.3048 -0.1016)
			(stroke
				(width 0.1)
				(type default)
			)
			(layer "F.Fab")
		)
		(fp_line
			(start -0.3048 -0.1016)
			(end -0.3048 0.9906)
			(stroke
				(width 0.1)
				(type default)
			)
			(layer "F.Fab")
		)
		(fp_line
			(start 0.3048 0.9906)
			(end 0.3048 -0.1016)
			(stroke
				(width 0.1)
				(type default)
			)
			(layer "F.Fab")
		)
		(fp_line
			(start -0.3048 0.9906)
			(end 0.3048 0.9906)
			(stroke
				(width 0.1)
				(type default)
			)
			(layer "F.Fab")
		)
		(pad "1" smd rect
			(at 0 0 90)
			(size 0.508 0.508)
			(layers "F.Cu" "F.Mask" "F.Paste")
			(net "P5V_STBY")
		)
		(pad "2" smd rect
			(at 0 0.889 90)
			(size 0.508 0.508)
			(layers "F.Cu" "F.Mask" "F.Paste")
			(net "GND")
		)
		(zone
			(layer "F.Cu")
			(hatch none 0.5)
			(connect_pads
				(clearance 0)
			)
			(min_thickness 0.25)
			(keepout
				(tracks not_allowed)
				(vias allowed)
				(pads allowed)
				(copperpour not_allowed)
				(footprints allowed)
			)
			(placement
				(enabled no)
				(sheetname "")
			)
			(fill
				(thermal_gap 0.5)
				(thermal_bridge_width 0.5)
				(island_removal_mode 0)
			)
			(polygon
				(pts
					(xy 2.286 -143.51) (xy 1.905 -143.51) (xy 1.905 -143.002) (xy 2.286 -143.002)
				)
			)
		)
		(zone
			(layer "F.Cu")
			(hatch none 0.5)
			(connect_pads
				(clearance 0)
			)
			(min_thickness 0.25)
			(keepout
				(tracks allowed)
				(vias not_allowed)
				(pads allowed)
				(copperpour not_allowed)
				(footprints allowed)
			)
			(placement
				(enabled no)
				(sheetname "")
			)
			(fill
				(thermal_gap 0.5)
				(thermal_bridge_width 0.5)
				(island_removal_mode 0)
			)
			(polygon
				(pts
					(xy 2.286 -143.51) (xy 1.905 -143.51) (xy 1.905 -143.002) (xy 2.286 -143.002)
				)
			)
		)
	)
	(footprint ""
		(layer "F.Cu")
		(at 347.850206 -2.254504 90)
		(property "Reference" "C7G40"
			(at 0 0 90)
			(layer "F.SilkS")
			(hide yes)
			(effects
				(font
					(size 1.27 1.27)
				)
			)
		)
		(property "Value" ""
			(at 0 0 90)
			(layer "F.Fab")
			(effects
				(font
					(size 1.27 1.27)
				)
			)
		)
		(duplicate_pad_numbers_are_jumpers no)
		(fp_poly
			(pts
				(xy 0.3048 -0.1016) (xy 0.3048 0.9906) (xy -0.3048 0.9906) (xy -0.3048 -0.1016)
			)
			(stroke
				(width 0)
				(type default)
			)
			(fill no)
			(layer "F.CrtYd")
		)
		(fp_line
			(start 0.3048 -0.1016)
			(end -0.3048 -0.1016)
			(stroke
				(width 0.1)
				(type default)
			)
			(layer "F.Fab")
		)
		(fp_line
			(start -0.3048 -0.1016)
			(end -0.3048 0.9906)
			(stroke
				(width 0.1)
				(type default)
			)
			(layer "F.Fab")
		)
		(fp_line
			(start 0.3048 0.9906)
			(end 0.3048 -0.1016)
			(stroke
				(width 0.1)
				(type default)
			)
			(layer "F.Fab")
		)
		(fp_line
			(start -0.3048 0.9906)
			(end 0.3048 0.9906)
			(stroke
				(width 0.1)
				(type default)
			)
			(layer "F.Fab")
		)
		(pad "1" smd rect
			(at 0 0 90)
			(size 0.508 0.508)
			(layers "F.Cu" "F.Mask" "F.Paste")
			(net "VR_PVDDQ_ABC_PH2_VCIN")
		)
		(pad "2" smd rect
			(at 0 0.889 90)
			(size 0.508 0.508)
			(layers "F.Cu" "F.Mask" "F.Paste")
			(net "GND")
		)
		(zone
			(layer "F.Cu")
			(hatch none 0.5)
			(connect_pads
				(clearance 0)
			)
			(min_thickness 0.25)
			(keepout
				(tracks allowed)
				(vias not_allowed)
				(pads allowed)
				(copperpour not_allowed)
				(footprints allowed)
			)
			(placement
				(enabled no)
				(sheetname "")
			)
			(fill
				(thermal_gap 0.5)
				(thermal_bridge_width 0.5)
				(island_removal_mode 0)
			)
			(polygon
				(pts
					(xy 348.104206 -2.000504) (xy 348.104206 -2.508504) (xy 348.485206 -2.508504) (xy 348.485206 -2.000504)
				)
			)
		)
		(zone
			(layer "F.Cu")
			(hatch none 0.5)
			(connect_pads
				(clearance 0)
			)
			(min_thickness 0.25)
			(keepout
				(tracks not_allowed)
				(vias allowed)
				(pads allowed)
				(copperpour not_allowed)
				(footprints allowed)
			)
			(placement
				(enabled no)
				(sheetname "")
			)
			(fill
				(thermal_gap 0.5)
				(thermal_bridge_width 0.5)
				(island_removal_mode 0)
			)
			(polygon
				(pts
					(xy 348.485206 -2.000504) (xy 348.485206 -2.508504) (xy 348.104206 -2.508504) (xy 348.104206 -2.000504)
				)
			)
		)
	)
	(footprint ""
		(layer "F.Cu")
		(at 195.165218 -86.502748)
		(property "Reference" "CT36"
			(at -4.29387 -6.096 270)
			(unlocked yes)
			(layer "F.SilkS")
			(effects
				(font
					(size 0.7874 0.5842)
					(thickness 0.1524)
				)
				(justify left)
			)
		)
		(property "Value" ""
			(at 0 0 0)
			(layer "F.Fab")
			(effects
				(font
					(size 1.27 1.27)
				)
			)
		)
		(duplicate_pad_numbers_are_jumpers no)
		(fp_poly
			(pts
				(xy 0.3048 -0.1016) (xy 0.3048 0.9906) (xy -0.3048 0.9906) (xy -0.3048 -0.1016)
			)
			(stroke
				(width 0)
				(type default)
			)
			(fill no)
			(layer "F.CrtYd")
		)
		(fp_line
			(start -0.3048 -0.1016)
			(end -0.3048 0.9906)
			(stroke
				(width 0.1)
				(type default)
			)
			(layer "F.Fab")
		)
		(fp_line
			(start -0.3048 0.9906)
			(end 0.3048 0.9906)
			(stroke
				(width 0.1)
				(type default)
			)
			(layer "F.Fab")
		)
		(fp_line
			(start 0.3048 -0.1016)
			(end -0.3048 -0.1016)
			(stroke
				(width 0.1)
				(type default)
			)
			(layer "F.Fab")
		)
		(fp_line
			(start 0.3048 0.9906)
			(end 0.3048 -0.1016)
			(stroke
				(width 0.1)
				(type default)
			)
			(layer "F.Fab")
		)
		(pad "1" smd rect
			(at 0 0)
			(size 0.508 0.508)
			(layers "F.Cu" "F.Mask" "F.Paste")
			(net "VR_PVCCIN_CPU0_AIREF5")
		)
		(pad "2" smd rect
			(at 0 0.889)
			(size 0.508 0.508)
			(layers "F.Cu" "F.Mask" "F.Paste")
			(net "GND")
		)
		(zone
			(layer "F.Cu")
			(hatch none 0.5)
			(connect_pads
				(clearance 0)
			)
			(min_thickness 0.25)
			(keepout
				(tracks allowed)
				(vias not_allowed)
				(pads allowed)
				(copperpour not_allowed)
				(footprints allowed)
			)
			(placement
				(enabled no)
				(sheetname "")
			)
			(fill
				(thermal_gap 0.5)
				(thermal_bridge_width 0.5)
				(island_removal_mode 0)
			)
			(polygon
				(pts
					(xy 194.911218 -86.248748) (xy 195.419218 -86.248748) (xy 195.419218 -85.867748) (xy 194.911218 -85.867748)
				)
			)
		)
		(zone
			(layer "F.Cu")
			(hatch none 0.5)
			(connect_pads
				(clearance 0)
			)
			(min_thickness 0.25)
			(keepout
				(tracks not_allowed)
				(vias allowed)
				(pads allowed)
				(copperpour not_allowed)
				(footprints allowed)
			)
			(placement
				(enabled no)
				(sheetname "")
			)
			(fill
				(thermal_gap 0.5)
				(thermal_bridge_width 0.5)
				(island_removal_mode 0)
			)
			(polygon
				(pts
					(xy 194.911218 -85.867748) (xy 195.419218 -85.867748) (xy 195.419218 -86.248748) (xy 194.911218 -86.248748)
				)
			)
		)
	)
)
